G04*
G04 #@! TF.GenerationSoftware,Altium Limited,Altium Designer,23.6.0 (18)*
G04*
G04 Layer_Color=8421504*
%FSLAX44Y44*%
%MOMM*%
G71*
G04*
G04 #@! TF.SameCoordinates,0D6CC9A4-690D-4EF8-AA6E-9FB67146BD04*
G04*
G04*
G04 #@! TF.FilePolarity,Positive*
G04*
G01*
G75*
%ADD16R,6.9000X10.4500*%
%ADD17R,2.5500X1.0500*%
%ADD18R,1.5000X1.0000*%
%ADD19R,0.4500X0.4500*%
%ADD20R,1.2500X0.8500*%
%ADD21R,0.6500X1.2500*%
G04:AMPARAMS|DCode=22|XSize=2.3mm|YSize=1.2mm|CornerRadius=0.36mm|HoleSize=0mm|Usage=FLASHONLY|Rotation=90.000|XOffset=0mm|YOffset=0mm|HoleType=Round|Shape=RoundedRectangle|*
%AMROUNDEDRECTD22*
21,1,2.3000,0.4800,0,0,90.0*
21,1,1.5800,1.2000,0,0,90.0*
1,1,0.7200,0.2400,0.7900*
1,1,0.7200,0.2400,-0.7900*
1,1,0.7200,-0.2400,-0.7900*
1,1,0.7200,-0.2400,0.7900*
%
%ADD22ROUNDEDRECTD22*%
G04:AMPARAMS|DCode=23|XSize=2.8mm|YSize=1.2mm|CornerRadius=0.36mm|HoleSize=0mm|Usage=FLASHONLY|Rotation=90.000|XOffset=0mm|YOffset=0mm|HoleType=Round|Shape=RoundedRectangle|*
%AMROUNDEDRECTD23*
21,1,2.8000,0.4800,0,0,90.0*
21,1,2.0800,1.2000,0,0,90.0*
1,1,0.7200,0.2400,1.0400*
1,1,0.7200,0.2400,-1.0400*
1,1,0.7200,-0.2400,-1.0400*
1,1,0.7200,-0.2400,1.0400*
%
%ADD23ROUNDEDRECTD23*%
%ADD24R,2.7000X1.1500*%
%ADD25R,0.6200X0.5700*%
%ADD26R,0.4400X0.4200*%
%ADD27R,3.4000X2.7000*%
%ADD28C,1.5000*%
%ADD29R,2.2300X1.8000*%
%ADD30R,1.6500X1.3000*%
%ADD31R,0.9500X1.0000*%
%ADD32R,1.0000X0.9500*%
%ADD33R,0.6200X0.6000*%
%ADD34R,1.3000X1.6500*%
%ADD35R,0.6000X0.6200*%
%ADD36R,0.5700X0.6200*%
G04:AMPARAMS|DCode=37|XSize=0.57mm|YSize=0.62mm|CornerRadius=0mm|HoleSize=0mm|Usage=FLASHONLY|Rotation=45.000|XOffset=0mm|YOffset=0mm|HoleType=Round|Shape=Rectangle|*
%AMROTATEDRECTD37*
4,1,4,0.0177,-0.4207,-0.4207,0.0177,-0.0177,0.4207,0.4207,-0.0177,0.0177,-0.4207,0.0*
%
%ADD37ROTATEDRECTD37*%

%ADD38R,0.4200X0.4400*%
D16*
X331693Y84089D02*
D03*
D17*
X230693Y58689D02*
D03*
Y84089D02*
D03*
Y109489D02*
D03*
D18*
X145500Y88750D02*
D03*
Y56750D02*
D03*
D19*
X308750Y489250D02*
D03*
X316750D02*
D03*
X343250Y488750D02*
D03*
X335250D02*
D03*
X112250Y463508D02*
D03*
X104250D02*
D03*
X123750D02*
D03*
X131750D02*
D03*
D20*
X301250Y464000D02*
D03*
Y438600D02*
D03*
X358750Y464000D02*
D03*
Y438600D02*
D03*
D21*
X342700Y470050D02*
D03*
X330000D02*
D03*
X317300D02*
D03*
X342700Y432550D02*
D03*
X330000D02*
D03*
X317300D02*
D03*
D22*
X273500Y274811D02*
D03*
Y226811D02*
D03*
X258500Y226811D02*
D03*
X243500Y226811D02*
D03*
X228500D02*
D03*
X258500Y274811D02*
D03*
X243500Y274811D02*
D03*
X213500D02*
D03*
X228500Y274811D02*
D03*
D23*
X213500Y229311D02*
D03*
D24*
X34250Y104750D02*
D03*
Y133750D02*
D03*
D25*
X457000Y412076D02*
D03*
Y421676D02*
D03*
D26*
X466849Y435727D02*
D03*
X473649D02*
D03*
D27*
X167947Y257371D02*
D03*
Y333571D02*
D03*
X167947Y384471D02*
D03*
X401947D02*
D03*
Y206471D02*
D03*
X401947Y295471D02*
D03*
X167947Y206471D02*
D03*
D28*
X315250Y259250D02*
D03*
X315250Y319250D02*
D03*
X355250D02*
D03*
X355250Y259250D02*
D03*
X282750Y379249D02*
D03*
X282750Y319250D02*
D03*
X315250Y319250D02*
D03*
X315250Y379249D02*
D03*
D29*
X72000Y147450D02*
D03*
Y118250D02*
D03*
X109500Y147450D02*
D03*
Y118250D02*
D03*
X144750Y119650D02*
D03*
X144750Y148850D02*
D03*
D30*
X192250Y38250D02*
D03*
Y56250D02*
D03*
D31*
X315000Y218811D02*
D03*
X331000Y218811D02*
D03*
X213500Y309061D02*
D03*
X229500D02*
D03*
D32*
X271250Y448300D02*
D03*
Y464300D02*
D03*
D33*
X285250Y464250D02*
D03*
Y455050D02*
D03*
X168750Y42690D02*
D03*
Y51890D02*
D03*
X431167Y384149D02*
D03*
X431167Y374949D02*
D03*
X346750Y379100D02*
D03*
Y369900D02*
D03*
D34*
X34250Y237000D02*
D03*
X52250D02*
D03*
X34250Y211750D02*
D03*
X52250D02*
D03*
D35*
X213500Y295561D02*
D03*
X222700D02*
D03*
X315226Y232063D02*
D03*
X324426Y232063D02*
D03*
D36*
X213500Y196772D02*
D03*
X223100D02*
D03*
X447400Y435726D02*
D03*
X457000Y435727D02*
D03*
D37*
X293462Y298212D02*
D03*
X300250Y305000D02*
D03*
D38*
X240792Y457200D02*
D03*
Y464000D02*
D03*
M02*
